M48
INCH,TZ
T01C.01
T02C.02
T03C.028
T04C.026
T05C.04
T06C.086
T07C.165
;LEADER: 12 
;HEADER: 
;CODE  : ASCII 
;FILE  : 16368-sb-1-6.drl for board 16368-sb.brd ... layers TOP and BOTTOM
;T01 Holesize 1. = 10.000000 Tolerance = +0.000000/-0.000000 PLATED MILS Quantity = 76
;T02 Holesize 2. = 20.000000 Tolerance = +0.000000/-0.000000 PLATED MILS Quantity = 16
;T03 Holesize 3. = 28.000000 Tolerance = +0.000000/-0.000000 PLATED MILS Quantity = 4
;T04 Holesize 4. = 26.000000 Tolerance = +0.000000/-0.000000 NON_PLATED MILS Quantity = 1
;T05 Holesize 5. = 40.000000 Tolerance = +0.000000/-0.000000 NON_PLATED MILS Quantity = 2
;T06 Holesize 6. = 86.000000 Tolerance = +0.000000/-0.000000 NON_PLATED MILS Quantity = 2
;T07 Holesize 7. = 165.000000 Tolerance = +0.000000/-0.000000 NON_PLATED MILS Quantity = 2
%
G90
T01
X35000Y5000
X41200Y7400
X53437Y13900
X68500Y13800
X69000Y17200
X70700Y11200
X71405Y19607
X81500Y12700
X84100Y14900
X95400Y12500
X98200Y16500
X109000Y11000
X118300Y19900
X131000Y6000
X133500Y15700
X134200Y9000
X137000Y12750
X143000Y5000
X145000Y36500
X127500Y37000
X119500Y33900
X119400Y29800
X111700Y39600
X108140Y28132
X103700Y36400
X98700Y21000
X98000Y25500
X95300Y21000
X88940Y39400
X85100Y21100
X84700Y26702
X79940Y26850
X76000Y37750
X74200Y21700
X74000Y34900
X68750Y24100
X65800Y21000
X65300Y24437
X58000Y38500
X56200Y21000
X54500Y25500
X52800Y21000
X46000Y25600
X45250Y35850
X40100Y21692
X39300Y35500
X28100Y39300
X5000Y38000
Y55000
X15000Y45000
X20000Y55000
X28100Y55300
X30827Y47067
X34200Y47000
X36733Y47067
X39400Y46831
X44607
X47200Y47067
X49730Y46821
X52218Y47067
X56000Y55500
X61300Y47250
X87700Y43400
X87900Y53100
X93000Y49700
X94800Y46800
X96000Y55600
X103655Y52264
X111800
X119403
X127500
X135500Y45000
X145000Y55000
X155000Y45000
X165000Y55000
X170000Y45000
T02
X11317Y8600
X6632Y13285
Y26085
X11317Y30770
X24117
X28802Y26085
Y13285
X24117Y8600
X153049
X148364Y13285
Y26085
X153049Y30770
X165849
X170534Y26085
Y13285
X165849Y8600
T03
X32205Y38484
Y55414
X51103
Y38484
T04
X26890Y46949
T05
X103642Y43898
X127264
T06
X9000Y48000
X164500Y48500
T07
X17717Y19685
X159449
M30
